(kicad_pcb
	(version 20260206)
	(generator "pcbnew")
	(generator_version "10.0")
	(general
		(thickness 1.6)
		(legacy_teardrops no)
	)
	(paper "A4")
	(title_block
		(title "Bryce Canyon_R.DPB_16317-1_OCP.brd")
		(comment 1 "Bryce Canyon / footprints 1-7 of 2099")
	)
	(layers
		(0 "F.Cu" signal "TOP")
		(4 "In1.Cu" signal "L2GND")
		(6 "In2.Cu" signal "L3")
		(8 "In3.Cu" signal "L4VCC")
		(10 "In4.Cu" signal "L5VCC")
		(12 "In5.Cu" signal "L6")
		(14 "In6.Cu" signal "L7GND")
		(2 "B.Cu" signal "BOTTOM")
		(9 "F.Adhes" user "F.Adhesive")
		(11 "B.Adhes" user "B.Adhesive")
		(13 "F.Paste" user "Package Geometry/Pastemask Top")
		(15 "B.Paste" user "Package Geometry/Pastemask Bottom")
		(5 "F.SilkS" user "Ref Des/Silkscreen Top")
		(7 "B.SilkS" user "Ref Des/Silkscreen Bottom")
		(1 "F.Mask" user "Board Geometry/Soldermask Top")
		(3 "B.Mask" user "Board Geometry/Soldermask Bottom")
		(17 "Dwgs.User" user "User.Drawings")
		(19 "Cmts.User" user "User.Comments")
		(21 "Eco1.User" user "User.Eco1")
		(23 "Eco2.User" user "User.Eco2")
		(25 "Edge.Cuts" user "Board Geometry/Outline")
		(27 "Margin" user)
		(31 "F.CrtYd" user "Package Geometry/Place Bound Top")
		(29 "B.CrtYd" user "Package Geometry/Place Bound Bottom")
		(35 "F.Fab" user "Ref Des/Assembly Top")
		(33 "B.Fab" user "Ref Des/Assembly Bottom")
	)
	(footprint ""
		(layer "F.Cu")
		(at 459.149704 -375.93524)
		(property "Reference" "R188"
			(at 0 0 0)
			(layer "F.SilkS")
			(hide yes)
			(effects
				(font
					(size 1.27 1.27)
				)
			)
		)
		(property "Value" "4K7R2F-GP"
			(at 0.064008 -3.993896 0)
			(unlocked yes)
			(layer "F.Fab")
			(hide yes)
			(effects
				(font
					(size 1.016 1.016)
					(thickness 0.1524)
				)
			)
		)
		(property "Device Type" "R402H16"
			(at 0.064008 -5.517896 0)
			(unlocked yes)
			(layer "F.Fab")
			(hide yes)
			(effects
				(font
					(size 1.016 1.016)
					(thickness 0.1524)
				)
			)
		)
		(duplicate_pad_numbers_are_jumpers no)
		(fp_line
			(start -0.508 -0.9398)
			(end -0.508 0.9398)
			(stroke
				(width 0.1524)
				(type default)
			)
			(layer "F.SilkS")
		)
		(fp_line
			(start 0.508 -0.9398)
			(end -0.508 -0.9398)
			(stroke
				(width 0.1524)
				(type default)
			)
			(layer "F.SilkS")
		)
		(fp_rect
			(start -0.508 0.9398)
			(end 0.508 -0.9398)
			(stroke
				(width 0)
				(type default)
			)
			(fill no)
			(layer "F.CrtYd")
		)
		(fp_rect
			(start -0.508 0.9398)
			(end 0.508 -0.9398)
			(stroke
				(width 0)
				(type default)
			)
			(fill no)
			(layer "F.Fab")
		)
		(pad "1" smd custom
			(at 0 -0.4445)
			(size 0.1397 0.1397)
			(layers "F.Cu" "F.Mask" "F.Paste")
			(net "FAN_BLUE_LED3")
			(options
				(clearance outline)
				(anchor circle)
			)
			(primitives
				(gr_poly
					(pts
						(arc
							(start -0.1778 -0.2794)
							(mid -0.249642 -0.249642)
							(end -0.2794 -0.1778)
						)
						(arc
							(start -0.2794 0.1778)
							(mid -0.249642 0.249642)
							(end -0.1778 0.2794)
						)
						(arc
							(start 0.1778 0.2794)
							(mid 0.249642 0.249642)
							(end 0.2794 0.1778)
						)
						(arc
							(start 0.2794 -0.1778)
							(mid 0.249642 -0.249642)
							(end 0.1778 -0.2794)
						)
					)
					(width 0)
					(fill yes)
				)
			)
		)
		(pad "2" smd custom
			(at 0 0.4445)
			(size 0.1397 0.1397)
			(layers "F.Cu" "F.Mask" "F.Paste")
			(net "P12V_IN")
			(options
				(clearance outline)
				(anchor circle)
			)
			(primitives
				(gr_poly
					(pts
						(arc
							(start -0.1778 -0.2794)
							(mid -0.249642 -0.249642)
							(end -0.2794 -0.1778)
						)
						(arc
							(start -0.2794 0.1778)
							(mid -0.249642 0.249642)
							(end -0.1778 0.2794)
						)
						(arc
							(start 0.1778 0.2794)
							(mid 0.249642 0.249642)
							(end 0.2794 0.1778)
						)
						(arc
							(start 0.2794 -0.1778)
							(mid 0.249642 -0.249642)
							(end 0.1778 -0.2794)
						)
					)
					(width 0)
					(fill yes)
				)
			)
		)
	)
	(footprint ""
		(layer "F.Cu")
		(at 246.898668 -223.393)
		(property "Reference" "R113"
			(at 0 0 0)
			(layer "F.SilkS")
			(hide yes)
			(effects
				(font
					(size 1.27 1.27)
				)
			)
		)
		(property "Value" "4K7R2F-GP"
			(at 0.064008 -3.993896 0)
			(unlocked yes)
			(layer "F.Fab")
			(hide yes)
			(effects
				(font
					(size 1.016 1.016)
					(thickness 0.1524)
				)
			)
		)
		(property "Device Type" "R402H16"
			(at 0.064008 -5.517896 0)
			(unlocked yes)
			(layer "F.Fab")
			(hide yes)
			(effects
				(font
					(size 1.016 1.016)
					(thickness 0.1524)
				)
			)
		)
		(duplicate_pad_numbers_are_jumpers no)
		(fp_line
			(start -0.508 -0.9398)
			(end -0.508 0.9398)
			(stroke
				(width 0.1524)
				(type default)
			)
			(layer "F.SilkS")
		)
		(fp_line
			(start 0.508 -0.9398)
			(end -0.508 -0.9398)
			(stroke
				(width 0.1524)
				(type default)
			)
			(layer "F.SilkS")
		)
		(fp_rect
			(start -0.508 0.9398)
			(end 0.508 -0.9398)
			(stroke
				(width 0)
				(type default)
			)
			(fill no)
			(layer "F.CrtYd")
		)
		(fp_rect
			(start -0.508 0.9398)
			(end 0.508 -0.9398)
			(stroke
				(width 0)
				(type default)
			)
			(fill no)
			(layer "F.Fab")
		)
		(pad "1" smd custom
			(at 0 -0.4445)
			(size 0.1397 0.1397)
			(layers "F.Cu" "F.Mask" "F.Paste")
			(net "P3V3_STBY_B")
			(options
				(clearance outline)
				(anchor circle)
			)
			(primitives
				(gr_poly
					(pts
						(arc
							(start -0.1778 -0.2794)
							(mid -0.249642 -0.249642)
							(end -0.2794 -0.1778)
						)
						(arc
							(start -0.2794 0.1778)
							(mid -0.249642 0.249642)
							(end -0.1778 0.2794)
						)
						(arc
							(start 0.1778 0.2794)
							(mid 0.249642 0.249642)
							(end 0.2794 0.1778)
						)
						(arc
							(start 0.2794 -0.1778)
							(mid 0.249642 -0.249642)
							(end 0.1778 -0.2794)
						)
					)
					(width 0)
					(fill yes)
				)
			)
		)
		(pad "2" smd custom
			(at 0 0.4445)
			(size 0.1397 0.1397)
			(layers "F.Cu" "F.Mask" "F.Paste")
			(net "EEPROM_A2")
			(options
				(clearance outline)
				(anchor circle)
			)
			(primitives
				(gr_poly
					(pts
						(arc
							(start -0.1778 -0.2794)
							(mid -0.249642 -0.249642)
							(end -0.2794 -0.1778)
						)
						(arc
							(start -0.2794 0.1778)
							(mid -0.249642 0.249642)
							(end -0.1778 0.2794)
						)
						(arc
							(start 0.1778 0.2794)
							(mid 0.249642 0.249642)
							(end 0.2794 0.1778)
						)
						(arc
							(start 0.2794 -0.1778)
							(mid 0.249642 -0.249642)
							(end 0.1778 -0.2794)
						)
					)
					(width 0)
					(fill yes)
				)
			)
		)
	)
	(footprint ""
		(layer "F.Cu")
		(at 394.6398 -16.0782 -90)
		(property "Reference" "C454"
			(at 0 0 270)
			(layer "F.SilkS")
			(hide yes)
			(effects
				(font
					(size 1.27 1.27)
				)
			)
		)
		(property "Value" "SCD033U25V2KX-GP"
			(at 1.1811 -2.7051 270)
			(unlocked yes)
			(layer "F.Fab")
			(hide yes)
			(effects
				(font
					(size 1.016 1.016)
					(thickness 0.1524)
				)
			)
		)
		(property "Device Type" "C402H22"
			(at 1.1811 -4.2291 270)
			(unlocked yes)
			(layer "F.Fab")
			(hide yes)
			(effects
				(font
					(size 1.016 1.016)
					(thickness 0.1524)
				)
			)
		)
		(duplicate_pad_numbers_are_jumpers no)
		(fp_rect
			(start -0.4318 0.9525)
			(end 0.4318 -0.9525)
			(stroke
				(width 0)
				(type default)
			)
			(fill no)
			(layer "F.CrtYd")
		)
		(fp_rect
			(start -0.4318 0.9525)
			(end 0.4318 -0.9525)
			(stroke
				(width 0)
				(type default)
			)
			(fill no)
			(layer "F.Fab")
		)
		(pad "1" smd custom
			(at 0 -0.4445 270)
			(size 0.1524 0.1524)
			(layers "F.Cu" "F.Mask" "F.Paste")
			(net "SW_HDD_P32")
			(options
				(clearance outline)
				(anchor circle)
			)
			(primitives
				(gr_poly
					(pts
						(arc
							(start 0.3048 -0.2032)
							(mid 0.275042 -0.275042)
							(end 0.2032 -0.3048)
						)
						(arc
							(start -0.2032 -0.3048)
							(mid -0.275042 -0.275042)
							(end -0.3048 -0.2032)
						)
						(arc
							(start -0.3048 0.2032)
							(mid -0.275042 0.275042)
							(end -0.2032 0.3048)
						)
						(arc
							(start 0.2032 0.3048)
							(mid 0.275042 0.275042)
							(end 0.3048 0.2032)
						)
					)
					(width 0)
					(fill yes)
				)
			)
		)
		(pad "2" smd custom
			(at 0 0.4445 270)
			(size 0.1524 0.1524)
			(layers "F.Cu" "F.Mask" "F.Paste")
			(net "GND")
			(options
				(clearance outline)
				(anchor circle)
			)
			(primitives
				(gr_poly
					(pts
						(arc
							(start 0.3048 -0.2032)
							(mid 0.275042 -0.275042)
							(end 0.2032 -0.3048)
						)
						(arc
							(start -0.2032 -0.3048)
							(mid -0.275042 -0.275042)
							(end -0.3048 -0.2032)
						)
						(arc
							(start -0.3048 0.2032)
							(mid -0.275042 0.275042)
							(end -0.2032 0.3048)
						)
						(arc
							(start 0.2032 0.3048)
							(mid 0.275042 0.275042)
							(end 0.3048 0.2032)
						)
					)
					(width 0)
					(fill yes)
				)
			)
		)
	)
	(footprint ""
		(layer "F.Cu")
		(at 14.859 -16.637 90)
		(property "Reference" "R636"
			(at 0 0 90)
			(layer "F.SilkS")
			(hide yes)
			(effects
				(font
					(size 1.27 1.27)
				)
			)
		)
		(property "Value" "4K7R2J-2-GP"
			(at 0.064008 -3.993896 90)
			(unlocked yes)
			(layer "F.Fab")
			(hide yes)
			(effects
				(font
					(size 1.016 1.016)
					(thickness 0.1524)
				)
			)
		)
		(property "Device Type" "R402H16"
			(at 0.064008 -5.517896 90)
			(unlocked yes)
			(layer "F.Fab")
			(hide yes)
			(effects
				(font
					(size 1.016 1.016)
					(thickness 0.1524)
				)
			)
		)
		(duplicate_pad_numbers_are_jumpers no)
		(fp_line
			(start 0.508 -0.9398)
			(end -0.508 -0.9398)
			(stroke
				(width 0.1524)
				(type default)
			)
			(layer "F.SilkS")
		)
		(fp_line
			(start -0.508 -0.9398)
			(end -0.508 0.9398)
			(stroke
				(width 0.1524)
				(type default)
			)
			(layer "F.SilkS")
		)
		(fp_rect
			(start -0.508 0.9398)
			(end 0.508 -0.9398)
			(stroke
				(width 0)
				(type default)
			)
			(fill no)
			(layer "F.CrtYd")
		)
		(fp_rect
			(start -0.508 0.9398)
			(end 0.508 -0.9398)
			(stroke
				(width 0)
				(type default)
			)
			(fill no)
			(layer "F.Fab")
		)
		(pad "1" smd custom
			(at 0 -0.4445 90)
			(size 0.1397 0.1397)
			(layers "F.Cu" "F.Mask" "F.Paste")
			(net "P12V_B")
			(options
				(clearance outline)
				(anchor circle)
			)
			(primitives
				(gr_poly
					(pts
						(arc
							(start -0.1778 -0.2794)
							(mid -0.249642 -0.249642)
							(end -0.2794 -0.1778)
						)
						(arc
							(start -0.2794 0.1778)
							(mid -0.249642 0.249642)
							(end -0.1778 0.2794)
						)
						(arc
							(start 0.1778 0.2794)
							(mid 0.249642 0.249642)
							(end 0.2794 0.1778)
						)
						(arc
							(start 0.2794 -0.1778)
							(mid 0.249642 -0.249642)
							(end 0.1778 -0.2794)
						)
					)
					(width 0)
					(fill yes)
				)
			)
		)
		(pad "2" smd custom
			(at 0 0.4445 90)
			(size 0.1397 0.1397)
			(layers "F.Cu" "F.Mask" "F.Paste")
			(net "SW_HDD_R24")
			(options
				(clearance outline)
				(anchor circle)
			)
			(primitives
				(gr_poly
					(pts
						(arc
							(start -0.1778 -0.2794)
							(mid -0.249642 -0.249642)
							(end -0.2794 -0.1778)
						)
						(arc
							(start -0.2794 0.1778)
							(mid -0.249642 0.249642)
							(end -0.1778 0.2794)
						)
						(arc
							(start 0.1778 0.2794)
							(mid 0.249642 0.249642)
							(end 0.2794 0.1778)
						)
						(arc
							(start 0.2794 -0.1778)
							(mid 0.249642 -0.249642)
							(end 0.1778 -0.2794)
						)
					)
					(width 0)
					(fill yes)
				)
			)
		)
	)
	(footprint ""
		(layer "F.Cu")
		(at 319.216024 -269.705074)
		(property "Reference" "TP51"
			(at 0 0 0)
			(layer "F.SilkS")
			(hide yes)
			(effects
				(font
					(size 1.27 1.27)
				)
			)
		)
		(property "Value" "*"
			(at -0.0508 -1.6764 0)
			(unlocked yes)
			(layer "F.Fab")
			(hide yes)
			(effects
				(font
					(size 1.016 1.016)
					(thickness 0.1524)
				)
			)
		)
		(property "Device Type" "TPAD32"
			(at -0.0508 -3.2004 0)
			(unlocked yes)
			(layer "F.Fab")
			(hide yes)
			(effects
				(font
					(size 1.016 1.016)
					(thickness 0.1524)
				)
			)
		)
		(duplicate_pad_numbers_are_jumpers no)
		(fp_poly
			(pts
				(arc
					(start 0.4064 0)
					(mid -0.4064 0)
					(end 0.4064 0)
				)
			)
			(stroke
				(width 0)
				(type default)
			)
			(fill no)
			(layer "F.CrtYd")
		)
		(fp_poly
			(pts
				(arc
					(start 0.7112 0)
					(mid -0.7112 0)
					(end 0.7112 0)
				)
			)
			(stroke
				(width 0)
				(type default)
			)
			(fill no)
			(layer "F.Fab")
		)
		(pad "1" smd circle
			(at 0 0)
			(size 0.8128 0.8128)
			(layers "F.Cu" "F.Mask" "F.Paste")
			(net "ACT_HDD_6")
		)
	)
	(footprint ""
		(layer "F.Cu")
		(at 143.002 -138.049 90)
		(property "Reference" "R445"
			(at 0 0 90)
			(layer "F.SilkS")
			(hide yes)
			(effects
				(font
					(size 1.27 1.27)
				)
			)
		)
		(property "Value" "4K7R2J-2-GP"
			(at 0.064008 -3.993896 90)
			(unlocked yes)
			(layer "F.Fab")
			(hide yes)
			(effects
				(font
					(size 1.016 1.016)
					(thickness 0.1524)
				)
			)
		)
		(property "Device Type" "R402H16"
			(at 0.064008 -5.517896 90)
			(unlocked yes)
			(layer "F.Fab")
			(hide yes)
			(effects
				(font
					(size 1.016 1.016)
					(thickness 0.1524)
				)
			)
		)
		(duplicate_pad_numbers_are_jumpers no)
		(fp_line
			(start 0.508 -0.9398)
			(end -0.508 -0.9398)
			(stroke
				(width 0.1524)
				(type default)
			)
			(layer "F.SilkS")
		)
		(fp_line
			(start -0.508 -0.9398)
			(end -0.508 0.9398)
			(stroke
				(width 0.1524)
				(type default)
			)
			(layer "F.SilkS")
		)
		(fp_rect
			(start -0.508 0.9398)
			(end 0.508 -0.9398)
			(stroke
				(width 0)
				(type default)
			)
			(fill no)
			(layer "F.CrtYd")
		)
		(fp_rect
			(start -0.508 0.9398)
			(end 0.508 -0.9398)
			(stroke
				(width 0)
				(type default)
			)
			(fill no)
			(layer "F.Fab")
		)
		(pad "1" smd custom
			(at 0 -0.4445 90)
			(size 0.1397 0.1397)
			(layers "F.Cu" "F.Mask" "F.Paste")
			(net "P12V_B")
			(options
				(clearance outline)
				(anchor circle)
			)
			(primitives
				(gr_poly
					(pts
						(arc
							(start -0.1778 -0.2794)
							(mid -0.249642 -0.249642)
							(end -0.2794 -0.1778)
						)
						(arc
							(start -0.2794 0.1778)
							(mid -0.249642 0.249642)
							(end -0.1778 0.2794)
						)
						(arc
							(start 0.1778 0.2794)
							(mid 0.249642 0.249642)
							(end 0.2794 0.1778)
						)
						(arc
							(start 0.2794 -0.1778)
							(mid 0.249642 -0.249642)
							(end 0.1778 -0.2794)
						)
					)
					(width 0)
					(fill yes)
				)
			)
		)
		(pad "2" smd custom
			(at 0 0.4445 90)
			(size 0.1397 0.1397)
			(layers "F.Cu" "F.Mask" "F.Paste")
			(net "SW_HDD_P16")
			(options
				(clearance outline)
				(anchor circle)
			)
			(primitives
				(gr_poly
					(pts
						(arc
							(start -0.1778 -0.2794)
							(mid -0.249642 -0.249642)
							(end -0.2794 -0.1778)
						)
						(arc
							(start -0.2794 0.1778)
							(mid -0.249642 0.249642)
							(end -0.1778 0.2794)
						)
						(arc
							(start 0.1778 0.2794)
							(mid 0.249642 0.249642)
							(end 0.2794 0.1778)
						)
						(arc
							(start 0.2794 -0.1778)
							(mid 0.249642 -0.249642)
							(end 0.1778 -0.2794)
						)
					)
					(width 0)
					(fill yes)
				)
			)
		)
	)
	(footprint ""
		(layer "F.Cu")
		(at 460.883 -16.3576 -90)
		(property "Reference" "R862"
			(at 0 0 270)
			(layer "F.SilkS")
			(hide yes)
			(effects
				(font
					(size 1.27 1.27)
				)
			)
		)
		(property "Value" "0R2J-2-GP"
			(at 0.064008 -3.993896 270)
			(unlocked yes)
			(layer "F.Fab")
			(hide yes)
			(effects
				(font
					(size 1.016 1.016)
					(thickness 0.1524)
				)
			)
		)
		(property "Device Type" "R402H16"
			(at 0.064008 -5.517896 270)
			(unlocked yes)
			(layer "F.Fab")
			(hide yes)
			(effects
				(font
					(size 1.016 1.016)
					(thickness 0.1524)
				)
			)
		)
		(duplicate_pad_numbers_are_jumpers no)
		(fp_line
			(start -0.508 -0.9398)
			(end -0.508 0.9398)
			(stroke
				(width 0.1524)
				(type default)
			)
			(layer "F.SilkS")
		)
		(fp_line
			(start 0.508 -0.9398)
			(end -0.508 -0.9398)
			(stroke
				(width 0.1524)
				(type default)
			)
			(layer "F.SilkS")
		)
		(fp_rect
			(start -0.508 0.9398)
			(end 0.508 -0.9398)
			(stroke
				(width 0)
				(type default)
			)
			(fill no)
			(layer "F.CrtYd")
		)
		(fp_rect
			(start -0.508 0.9398)
			(end 0.508 -0.9398)
			(stroke
				(width 0)
				(type default)
			)
			(fill no)
			(layer "F.Fab")
		)
		(pad "1" smd custom
			(at 0 -0.4445 270)
			(size 0.1397 0.1397)
			(layers "F.Cu" "F.Mask" "F.Paste")
			(net "DRIVE_B_34_PWR")
			(options
				(clearance outline)
				(anchor circle)
			)
			(primitives
				(gr_poly
					(pts
						(arc
							(start -0.1778 -0.2794)
							(mid -0.249642 -0.249642)
							(end -0.2794 -0.1778)
						)
						(arc
							(start -0.2794 0.1778)
							(mid -0.249642 0.249642)
							(end -0.1778 0.2794)
						)
						(arc
							(start 0.1778 0.2794)
							(mid 0.249642 0.249642)
							(end 0.2794 0.1778)
						)
						(arc
							(start 0.2794 -0.1778)
							(mid 0.249642 -0.249642)
							(end 0.1778 -0.2794)
						)
					)
					(width 0)
					(fill yes)
				)
			)
		)
		(pad "2" smd custom
			(at 0 0.4445 270)
			(size 0.1397 0.1397)
			(layers "F.Cu" "F.Mask" "F.Paste")
			(net "SW_PWR_R_HDD34")
			(options
				(clearance outline)
				(anchor circle)
			)
			(primitives
				(gr_poly
					(pts
						(arc
							(start -0.1778 -0.2794)
							(mid -0.249642 -0.249642)
							(end -0.2794 -0.1778)
						)
						(arc
							(start -0.2794 0.1778)
							(mid -0.249642 0.249642)
							(end -0.1778 0.2794)
						)
						(arc
							(start 0.1778 0.2794)
							(mid 0.249642 0.249642)
							(end 0.2794 0.1778)
						)
						(arc
							(start 0.2794 -0.1778)
							(mid 0.249642 -0.249642)
							(end 0.1778 -0.2794)
						)
					)
					(width 0)
					(fill yes)
				)
			)
		)
	)
)
